(kicad_pcb
	(version 20260206)
	(generator "pcbnew")
	(generator_version "10.0")
	(general
		(thickness 1.6)
		(legacy_teardrops no)
	)
	(paper "A4")
	(title_block
		(title "baseboard — 13948-1b.1110WZS1818.brd")
		(comment 1 "Honey Badger (Wiwynn) / footprints 786-789 of 2523")
	)
	(layers
		(0 "F.Cu" signal "TOP")
		(4 "In1.Cu" signal "L2GND")
		(6 "In2.Cu" signal "L3")
		(8 "In3.Cu" signal "L4VCC")
		(10 "In4.Cu" signal "L5VCC")
		(12 "In5.Cu" signal "L6")
		(14 "In6.Cu" signal "L7GND")
		(2 "B.Cu" signal "BOTTOM")
		(9 "F.Adhes" user "F.Adhesive")
		(11 "B.Adhes" user "B.Adhesive")
		(13 "F.Paste" user "Package Geometry/Pastemask Top")
		(15 "B.Paste" user "Package Geometry/Pastemask Bottom")
		(5 "F.SilkS" user "Ref Des/Silkscreen Top")
		(7 "B.SilkS" user "Ref Des/Silkscreen Bottom")
		(1 "F.Mask" user "Board Geometry/Soldermask Top")
		(3 "B.Mask" user "Board Geometry/Soldermask Bottom")
		(17 "Dwgs.User" user "User.Drawings")
		(19 "Cmts.User" user "User.Comments")
		(21 "Eco1.User" user "User.Eco1")
		(23 "Eco2.User" user "User.Eco2")
		(25 "Edge.Cuts" user "Board Geometry/Outline")
		(27 "Margin" user)
		(31 "F.CrtYd" user "Package Geometry/Place Bound Top")
		(29 "B.CrtYd" user "Package Geometry/Place Bound Bottom")
		(35 "F.Fab" user "Ref Des/Assembly Top")
		(33 "B.Fab" user "Ref Des/Assembly Bottom")
	)
	(footprint ""
		(layer "F.Cu")
		(at 183.315864 -30.806136)
		(property "Reference" "U20"
			(at 0 0 0)
			(layer "F.SilkS")
			(hide yes)
			(effects
				(font
					(size 1.27 1.27)
				)
			)
		)
		(property "Value" "BCM5221A4KMLG-2-GP-U"
			(at -5.3975 -7.2263 0)
			(unlocked yes)
			(layer "F.Fab")
			(hide yes)
			(effects
				(font
					(size 1.016 1.016)
					(thickness 0.1524)
				)
			)
		)
		(property "Device Type" "QFN48-1G4D8H40"
			(at -5.3975 -8.7503 0)
			(unlocked yes)
			(layer "F.Fab")
			(hide yes)
			(effects
				(font
					(size 1.016 1.016)
					(thickness 0.1524)
				)
			)
		)
		(duplicate_pad_numbers_are_jumpers no)
		(fp_line
			(start -4.5212 -4.5212)
			(end -4.5212 -3.2512)
			(stroke
				(width 0.1524)
				(type default)
			)
			(layer "F.SilkS")
		)
		(fp_line
			(start -4.5212 3.2512)
			(end -4.5212 4.5212)
			(stroke
				(width 0.1524)
				(type default)
			)
			(layer "F.SilkS")
		)
		(fp_line
			(start -4.5212 4.5212)
			(end -3.2512 4.5212)
			(stroke
				(width 0.1524)
				(type default)
			)
			(layer "F.SilkS")
		)
		(fp_line
			(start -4.2926 -1.749552)
			(end -4.8006 -1.749552)
			(stroke
				(width 0.1524)
				(type default)
			)
			(layer "F.SilkS")
		)
		(fp_line
			(start -4.2926 0.749808)
			(end -5.0546 0.749808)
			(stroke
				(width 0.1524)
				(type default)
			)
			(layer "F.SilkS")
		)
		(fp_line
			(start -3.2512 -4.5212)
			(end -4.5212 -4.5212)
			(stroke
				(width 0.1524)
				(type default)
			)
			(layer "F.SilkS")
		)
		(fp_line
			(start -2.749296 4.2926)
			(end -2.749296 4.8006)
			(stroke
				(width 0.1524)
				(type default)
			)
			(layer "F.SilkS")
		)
		(fp_line
			(start -1.749552 -4.2926)
			(end -1.749552 -5.0546)
			(stroke
				(width 0.1524)
				(type default)
			)
			(layer "F.SilkS")
		)
		(fp_line
			(start -0.249936 4.2926)
			(end -0.249936 5.0546)
			(stroke
				(width 0.1524)
				(type default)
			)
			(layer "F.SilkS")
		)
		(fp_line
			(start 0.749808 -4.2926)
			(end 0.749808 -4.8006)
			(stroke
				(width 0.1524)
				(type default)
			)
			(layer "F.SilkS")
		)
		(fp_line
			(start 2.249424 4.2926)
			(end 2.249424 4.8006)
			(stroke
				(width 0.1524)
				(type default)
			)
			(layer "F.SilkS")
		)
		(fp_line
			(start 3.2512 4.5212)
			(end 4.5212 4.5212)
			(stroke
				(width 0.1524)
				(type default)
			)
			(layer "F.SilkS")
		)
		(fp_line
			(start 4.2926 -1.24968)
			(end 4.8006 -1.24968)
			(stroke
				(width 0.1524)
				(type default)
			)
			(layer "F.SilkS")
		)
		(fp_line
			(start 4.2926 1.24968)
			(end 5.0546 1.24968)
			(stroke
				(width 0.1524)
				(type default)
			)
			(layer "F.SilkS")
		)
		(fp_line
			(start 4.5212 4.5212)
			(end 4.5212 3.2512)
			(stroke
				(width 0.1524)
				(type default)
			)
			(layer "F.SilkS")
		)
		(fp_poly
			(pts
				(xy 4.5212 -4.5212) (xy 3.2512 -4.5212) (xy 4.5212 -3.2512)
			)
			(stroke
				(width 0)
				(type default)
			)
			(fill yes)
			(layer "F.SilkS")
		)
		(fp_rect
			(start -3.5052 3.5052)
			(end 3.5052 -3.5052)
			(stroke
				(width 0)
				(type default)
			)
			(fill no)
			(layer "F.CrtYd")
		)
		(fp_poly
			(pts
				(xy -4.5212 4.5212) (xy -4.5212 -4.5212) (xy 4.5212 -4.5212) (xy 4.5212 -0.00254) (xy 3.5052 -0.00254)
				(xy 3.5052 -3.5052) (xy -3.5052 -3.5052) (xy -3.5052 3.5052) (xy 3.5052 3.5052) (xy 3.5052 0.00254)
				(xy 4.5212 0.00254) (xy 4.5212 4.5212)
			)
			(stroke
				(width 0)
				(type default)
			)
			(fill no)
			(layer "F.CrtYd")
		)
		(fp_rect
			(start -4.5212 4.5212)
			(end 4.5212 -4.5212)
			(stroke
				(width 0)
				(type default)
			)
			(fill no)
			(layer "F.Fab")
		)
		(pad "1" smd rect
			(at 2.750058 -3.556)
			(size 0.3048 0.9144)
			(layers "F.Cu" "F.Mask" "F.Paste")
			(net "RMII_BMC_CRS_DV_R")
		)
		(pad "2" smd rect
			(at 2.249932 -3.429)
			(size 0.3048 1.1684)
			(layers "F.Cu" "F.Mask" "F.Paste")
			(net "P3V3_STBY")
		)
		(pad "3" smd rect
			(at 1.75006 -3.429)
			(size 0.3048 1.1684)
			(layers "F.Cu" "F.Mask" "F.Paste")
			(net "CLK_50M_RMII_PHY")
		)
		(pad "4" smd rect
			(at 1.249934 -3.429)
			(size 0.3048 1.1684)
			(layers "F.Cu" "F.Mask" "F.Paste")
			(net "GND")
		)
		(pad "5" smd rect
			(at 0.750062 -3.429)
			(size 0.3048 1.1684)
			(layers "F.Cu" "F.Mask" "F.Paste")
			(net "Net_2069")
		)
		(pad "6" smd rect
			(at 0.249936 -3.429)
			(size 0.3048 1.1684)
			(layers "F.Cu" "F.Mask" "F.Paste")
			(net "PHY_RESET#")
		)
		(pad "7" smd rect
			(at -0.249936 -3.429)
			(size 0.3048 1.1684)
			(layers "F.Cu" "F.Mask" "F.Paste")
			(net "PHY_AD0")
		)
		(pad "8" smd rect
			(at -0.750062 -3.429)
			(size 0.3048 1.1684)
			(layers "F.Cu" "F.Mask" "F.Paste")
			(net "PHY_AD1")
		)
		(pad "9" smd rect
			(at -1.249934 -3.429)
			(size 0.3048 1.1684)
			(layers "F.Cu" "F.Mask" "F.Paste")
			(net "PHY_AD3")
		)
		(pad "10" smd rect
			(at -1.75006 -3.429)
			(size 0.3048 1.1684)
			(layers "F.Cu" "F.Mask" "F.Paste")
			(net "PHY_AD4")
		)
		(pad "11" smd rect
			(at -2.249932 -3.429)
			(size 0.3048 1.1684)
			(layers "F.Cu" "F.Mask" "F.Paste")
			(net "PHY_TEST_EN")
		)
		(pad "12" smd rect
			(at -2.750058 -3.556)
			(size 0.3048 0.9144)
			(layers "F.Cu" "F.Mask" "F.Paste")
			(net "PHY_LOW_PWR")
		)
		(pad "13" smd rect
			(at -3.556 -2.750058)
			(size 0.9144 0.3048)
			(layers "F.Cu" "F.Mask" "F.Paste")
			(net "NC_PHY_ENGY_DET")
		)
		(pad "14" smd rect
			(at -3.429 -2.249932)
			(size 1.1684 0.3048)
			(layers "F.Cu" "F.Mask" "F.Paste")
			(net "GND")
		)
		(pad "15" smd rect
			(at -3.429 -1.75006)
			(size 1.1684 0.3048)
			(layers "F.Cu" "F.Mask" "F.Paste")
			(net "P3V3_STBY")
		)
		(pad "16" smd rect
			(at -3.429 -1.249934)
			(size 1.1684 0.3048)
			(layers "F.Cu" "F.Mask" "F.Paste")
			(net "PHY_AVDD")
		)
		(pad "17" smd rect
			(at -3.429 -0.750062)
			(size 1.1684 0.3048)
			(layers "F.Cu" "F.Mask" "F.Paste")
			(net "BMC_PHY_RDAC")
		)
		(pad "18" smd rect
			(at -3.429 -0.249936)
			(size 1.1684 0.3048)
			(layers "F.Cu" "F.Mask" "F.Paste")
			(net "BCM5221_RX_C_DN")
		)
		(pad "19" smd rect
			(at -3.429 0.249936)
			(size 1.1684 0.3048)
			(layers "F.Cu" "F.Mask" "F.Paste")
			(net "BCM5221_RX_C_DP")
		)
		(pad "20" smd rect
			(at -3.429 0.750062)
			(size 1.1684 0.3048)
			(layers "F.Cu" "F.Mask" "F.Paste")
			(net "PHY_AVDD")
		)
		(pad "21" smd rect
			(at -3.429 1.249934)
			(size 1.1684 0.3048)
			(layers "F.Cu" "F.Mask" "F.Paste")
			(net "BCM5221_TX_C_DN")
		)
		(pad "22" smd rect
			(at -3.429 1.75006)
			(size 1.1684 0.3048)
			(layers "F.Cu" "F.Mask" "F.Paste")
			(net "BCM5221_TX_C_DP")
		)
		(pad "23" smd rect
			(at -3.429 2.249932)
			(size 1.1684 0.3048)
			(layers "F.Cu" "F.Mask" "F.Paste")
			(net "PHY_ACTLED_N")
		)
		(pad "24" smd rect
			(at -3.556 2.750058)
			(size 0.9144 0.3048)
			(layers "F.Cu" "F.Mask" "F.Paste")
			(net "NC_PHY_BMC_INTR_N")
		)
		(pad "25" smd rect
			(at -2.750058 3.556)
			(size 0.3048 0.9144)
			(layers "F.Cu" "F.Mask" "F.Paste")
			(net "PHY_LNKLED_N")
		)
		(pad "26" smd rect
			(at -2.249932 3.429)
			(size 0.3048 1.1684)
			(layers "F.Cu" "F.Mask" "F.Paste")
			(net "NC_PHYSPLOED_N")
		)
		(pad "27" smd rect
			(at -1.75006 3.429)
			(size 0.3048 1.1684)
			(layers "F.Cu" "F.Mask" "F.Paste")
			(net "PHY_F100")
		)
		(pad "28" smd rect
			(at -1.249934 3.429)
			(size 0.3048 1.1684)
			(layers "F.Cu" "F.Mask" "F.Paste")
			(net "PHY_ANEN")
		)
		(pad "29" smd rect
			(at -0.750062 3.429)
			(size 0.3048 1.1684)
			(layers "F.Cu" "F.Mask" "F.Paste")
			(net "PHY_FDX")
		)
		(pad "30" smd rect
			(at -0.249936 3.429)
			(size 0.3048 1.1684)
			(layers "F.Cu" "F.Mask" "F.Paste")
			(net "RMII_BMC_MDIO_R")
		)
		(pad "31" smd rect
			(at 0.249936 3.429)
			(size 0.3048 1.1684)
			(layers "F.Cu" "F.Mask" "F.Paste")
			(net "RMII_BMC_MDC_R")
		)
		(pad "32" smd rect
			(at 0.750062 3.429)
			(size 0.3048 1.1684)
			(layers "F.Cu" "F.Mask" "F.Paste")
			(net "Net_2072")
		)
		(pad "33" smd rect
			(at 1.249934 3.429)
			(size 0.3048 1.1684)
			(layers "F.Cu" "F.Mask" "F.Paste")
			(net "Net_2073")
		)
		(pad "34" smd rect
			(at 1.75006 3.429)
			(size 0.3048 1.1684)
			(layers "F.Cu" "F.Mask" "F.Paste")
			(net "P3V3_STBY")
		)
		(pad "35" smd rect
			(at 2.249932 3.429)
			(size 0.3048 1.1684)
			(layers "F.Cu" "F.Mask" "F.Paste")
			(net "RMII_PHY_BMC_RXD1_R")
		)
		(pad "36" smd rect
			(at 2.750058 3.556)
			(size 0.3048 0.9144)
			(layers "F.Cu" "F.Mask" "F.Paste")
			(net "RMII_PHY_BMC_RXD0_R")
		)
		(pad "37" smd rect
			(at 3.556 2.750058)
			(size 0.9144 0.3048)
			(layers "F.Cu" "F.Mask" "F.Paste")
			(net "Net_2074")
		)
		(pad "38" smd rect
			(at 3.429 2.249932)
			(size 1.1684 0.3048)
			(layers "F.Cu" "F.Mask" "F.Paste")
			(net "NC_PHY_RXC")
		)
		(pad "39" smd rect
			(at 3.429 1.75006)
			(size 1.1684 0.3048)
			(layers "F.Cu" "F.Mask" "F.Paste")
			(net "RMII_BMC_RX_ER_R")
		)
		(pad "40" smd rect
			(at 3.429 1.249934)
			(size 1.1684 0.3048)
			(layers "F.Cu" "F.Mask" "F.Paste")
			(net "PHY_TX_ER_PD")
		)
		(pad "41" smd rect
			(at 3.429 0.750062)
			(size 1.1684 0.3048)
			(layers "F.Cu" "F.Mask" "F.Paste")
			(net "NC_PHY_TXC")
		)
		(pad "42" smd rect
			(at 3.429 0.249936)
			(size 1.1684 0.3048)
			(layers "F.Cu" "F.Mask" "F.Paste")
			(net "PHY_DVDD")
		)
		(pad "43" smd rect
			(at 3.429 -0.249936)
			(size 1.1684 0.3048)
			(layers "F.Cu" "F.Mask" "F.Paste")
			(net "RMII_BMC_TX_EN")
		)
		(pad "44" smd rect
			(at 3.429 -0.750062)
			(size 1.1684 0.3048)
			(layers "F.Cu" "F.Mask" "F.Paste")
			(net "RMII_BMC_PHY_TXD0")
		)
		(pad "45" smd rect
			(at 3.429 -1.249934)
			(size 1.1684 0.3048)
			(layers "F.Cu" "F.Mask" "F.Paste")
			(net "RMII_BMC_PHY_TXD1")
		)
		(pad "46" smd rect
			(at 3.429 -1.75006)
			(size 1.1684 0.3048)
			(layers "F.Cu" "F.Mask" "F.Paste")
			(net "Net_2075")
		)
		(pad "47" smd rect
			(at 3.429 -2.249932)
			(size 1.1684 0.3048)
			(layers "F.Cu" "F.Mask" "F.Paste")
			(net "Net_2070")
		)
		(pad "48" smd rect
			(at 3.556 -2.750058)
			(size 0.9144 0.3048)
			(layers "F.Cu" "F.Mask" "F.Paste")
			(net "Net_2071")
		)
		(pad "49" smd rect
			(at 0 0)
			(size 4.8006 4.8006)
			(layers "F.Cu" "F.Mask" "F.Paste")
			(net "GND")
		)
	)
	(footprint ""
		(layer "F.Cu")
		(at 162.687 -101.473 180)
		(property "Reference" "PC181"
			(at 0 0 180)
			(layer "F.SilkS")
			(hide yes)
			(effects
				(font
					(size 1.27 1.27)
				)
			)
		)
		(property "Value" "SC47U6D3V5MX-1-GP"
			(at -0.0762 -6.1214 180)
			(unlocked yes)
			(layer "F.Fab")
			(hide yes)
			(effects
				(font
					(size 1.016 1.016)
					(thickness 0.1524)
				)
			)
		)
		(property "Device Type" "C805H54"
			(at -0.0762 -8.1534 180)
			(unlocked yes)
			(layer "F.Fab")
			(hide yes)
			(effects
				(font
					(size 1.016 1.016)
					(thickness 0.1524)
				)
			)
		)
		(duplicate_pad_numbers_are_jumpers no)
		(fp_line
			(start 0.635 0)
			(end -0.635 0)
			(stroke
				(width 0.508)
				(type default)
			)
			(layer "F.SilkS")
		)
		(fp_rect
			(start -0.9652 1.778)
			(end 0.9652 -1.778)
			(stroke
				(width 0)
				(type default)
			)
			(fill no)
			(layer "F.CrtYd")
		)
		(fp_poly
			(pts
				(xy -0.9652 -1.778) (xy 0.9652 -1.778) (xy 0.9652 1.778) (xy -0.9652 1.778)
			)
			(stroke
				(width 0)
				(type default)
			)
			(fill no)
			(layer "F.Fab")
		)
		(pad "1" smd rect
			(at 0 -0.9652 180)
			(size 1.397 1.143)
			(layers "F.Cu" "F.Mask" "F.Paste")
			(net "P0V9_E")
		)
		(pad "2" smd rect
			(at 0 0.9652 180)
			(size 1.397 1.143)
			(layers "F.Cu" "F.Mask" "F.Paste")
			(net "GND")
		)
	)
	(footprint ""
		(layer "F.Cu")
		(at 299.466 -102.108)
		(property "Reference" "R589"
			(at 0 0 0)
			(layer "F.SilkS")
			(hide yes)
			(effects
				(font
					(size 1.27 1.27)
				)
			)
		)
		(property "Value" "4K7R2F-GP"
			(at 0.064008 -3.993896 0)
			(unlocked yes)
			(layer "F.Fab")
			(hide yes)
			(effects
				(font
					(size 1.016 1.016)
					(thickness 0.1524)
				)
			)
		)
		(property "Device Type" "R402H16"
			(at 0.064008 -5.517896 0)
			(unlocked yes)
			(layer "F.Fab")
			(hide yes)
			(effects
				(font
					(size 1.016 1.016)
					(thickness 0.1524)
				)
			)
		)
		(duplicate_pad_numbers_are_jumpers no)
		(fp_line
			(start -0.508 -0.9398)
			(end -0.508 0.9398)
			(stroke
				(width 0.1524)
				(type default)
			)
			(layer "F.SilkS")
		)
		(fp_line
			(start 0.508 -0.9398)
			(end -0.508 -0.9398)
			(stroke
				(width 0.1524)
				(type default)
			)
			(layer "F.SilkS")
		)
		(fp_rect
			(start -0.508 0.9398)
			(end 0.508 -0.9398)
			(stroke
				(width 0)
				(type default)
			)
			(fill no)
			(layer "F.CrtYd")
		)
		(fp_rect
			(start -0.508 0.9398)
			(end 0.508 -0.9398)
			(stroke
				(width 0)
				(type default)
			)
			(fill no)
			(layer "F.Fab")
		)
		(pad "1" smd custom
			(at 0 -0.4445)
			(size 0.1397 0.1397)
			(layers "F.Cu" "F.Mask" "F.Paste")
			(net "P3V3_STBY")
			(options
				(clearance outline)
				(anchor circle)
			)
			(primitives
				(gr_poly
					(pts
						(arc
							(start -0.1778 -0.2794)
							(mid -0.249642 -0.249642)
							(end -0.2794 -0.1778)
						)
						(arc
							(start -0.2794 0.1778)
							(mid -0.249642 0.249642)
							(end -0.1778 0.2794)
						)
						(arc
							(start 0.1778 0.2794)
							(mid 0.249642 0.249642)
							(end 0.2794 0.1778)
						)
						(arc
							(start 0.2794 -0.1778)
							(mid 0.249642 -0.249642)
							(end 0.1778 -0.2794)
						)
					)
					(width 0)
					(fill yes)
				)
			)
		)
		(pad "2" smd custom
			(at 0 0.4445)
			(size 0.1397 0.1397)
			(layers "F.Cu" "F.Mask" "F.Paste")
			(net "TEMP_2_A0")
			(options
				(clearance outline)
				(anchor circle)
			)
			(primitives
				(gr_poly
					(pts
						(arc
							(start -0.1778 -0.2794)
							(mid -0.249642 -0.249642)
							(end -0.2794 -0.1778)
						)
						(arc
							(start -0.2794 0.1778)
							(mid -0.249642 0.249642)
							(end -0.1778 0.2794)
						)
						(arc
							(start 0.1778 0.2794)
							(mid 0.249642 0.249642)
							(end 0.2794 0.1778)
						)
						(arc
							(start 0.2794 -0.1778)
							(mid 0.249642 -0.249642)
							(end 0.1778 -0.2794)
						)
					)
					(width 0)
					(fill yes)
				)
			)
		)
	)
	(footprint ""
		(layer "F.Cu")
		(at 53.975 -201.549)
		(property "Reference" "C7274"
			(at 0 0 0)
			(layer "F.SilkS")
			(hide yes)
			(effects
				(font
					(size 1.27 1.27)
				)
			)
		)
		(property "Value" "SCD1U25V3KX-GP"
			(at 0 -2.8194 0)
			(unlocked yes)
			(layer "F.Fab")
			(hide yes)
			(effects
				(font
					(size 1.016 1.016)
					(thickness 0.1524)
				)
			)
		)
		(property "Device Type" "C603H36"
			(at 0 -4.3434 0)
			(unlocked yes)
			(layer "F.Fab")
			(hide yes)
			(effects
				(font
					(size 1.016 1.016)
					(thickness 0.1524)
				)
			)
		)
		(duplicate_pad_numbers_are_jumpers no)
		(fp_line
			(start 0.508 0)
			(end -0.508 0)
			(stroke
				(width 0.2032)
				(type default)
			)
			(layer "F.SilkS")
		)
		(fp_rect
			(start -0.5842 1.3335)
			(end 0.5842 -1.3335)
			(stroke
				(width 0)
				(type default)
			)
			(fill no)
			(layer "F.CrtYd")
		)
		(fp_rect
			(start -0.5842 1.3335)
			(end 0.5842 -1.3335)
			(stroke
				(width 0)
				(type default)
			)
			(fill no)
			(layer "F.Fab")
		)
		(pad "1" smd custom
			(at 0 -0.762)
			(size 0.2159 0.2159)
			(layers "F.Cu" "F.Mask" "F.Paste")
			(net "P12V_PCIE")
			(options
				(clearance outline)
				(anchor circle)
			)
			(primitives
				(gr_poly
					(pts
						(arc
							(start -0.3302 -0.4318)
							(mid -0.402042 -0.402042)
							(end -0.4318 -0.3302)
						)
						(arc
							(start -0.4318 0.3302)
							(mid -0.402042 0.402042)
							(end -0.3302 0.4318)
						)
						(arc
							(start 0.3302 0.4318)
							(mid 0.402042 0.402042)
							(end 0.4318 0.3302)
						)
						(arc
							(start 0.4318 -0.3302)
							(mid 0.402042 -0.402042)
							(end 0.3302 -0.4318)
						)
					)
					(width 0)
					(fill yes)
				)
			)
		)
		(pad "2" smd custom
			(at 0 0.762)
			(size 0.2159 0.2159)
			(layers "F.Cu" "F.Mask" "F.Paste")
			(net "GND")
			(options
				(clearance outline)
				(anchor circle)
			)
			(primitives
				(gr_poly
					(pts
						(arc
							(start -0.3302 -0.4318)
							(mid -0.402042 -0.402042)
							(end -0.4318 -0.3302)
						)
						(arc
							(start -0.4318 0.3302)
							(mid -0.402042 0.402042)
							(end -0.3302 0.4318)
						)
						(arc
							(start 0.3302 0.4318)
							(mid 0.402042 0.402042)
							(end 0.4318 0.3302)
						)
						(arc
							(start 0.4318 -0.3302)
							(mid 0.402042 -0.402042)
							(end 0.3302 -0.4318)
						)
					)
					(width 0)
					(fill yes)
				)
			)
		)
	)
)
